# T6G (Grand Teton) — schematic parts with pin connectivity, parts 4615–4631 of 8303; source: Cadence DE-HDL packaged netlist (pstxprt.dat, pstxnet.dat, pstchip.dat)

PU200  MAX15090BEWIT  MAX15090BEWI+T IC  pkg BGA28_0-5_3-525X2-065  page 140
  A1  ISENSE  OUT  = P3V3_OCP_SENSE_2
  A2  VCC  POWER  = P3V3_OCP_VCC_2
  A3  IN_A3  IN  = P3V3_AUX
  A4  OUT_A4  OUT  = P3V3_OCP_V3_2_R
  A5  IN_A5  IN  = P3V3_AUX
  A6  GATE  BI  = P3V3_OCP_GATE_2
  A7  CDLY  IN  = GND
  B1  CB  BI  = P3V3_OCP_CB_2
  B2  GND_B2  POWER  = GND
  B3  IN_B3  IN  = P3V3_AUX
  B4  OUT_B4  OUT  = P3V3_OCP_V3_2_R
  B5  IN_B5  IN  = P3V3_AUX
  B6  OUT_B6  OUT  = P3V3_OCP_V3_2_R
  B7  \en#\  IN  = GND
  C1  GND_C1  POWER  = GND
  C2  GND_C2  POWER  = GND
  C3  IN_C3  IN  = P3V3_AUX
  C4  OUT_C4  OUT  = P3V3_OCP_V3_2_R
  C5  IN_C5  IN  = P3V3_AUX
  C6  OUT_C6  OUT  = P3V3_OCP_V3_2_R
  C7  \fault#\  OUT  = P3V3_OCP_FAULT_2
  D1  REG  OUT  = P3V3_OCP_REG_2
  D2  UV  IN  = P3V3_OCP_UV_2
  D3  OV  IN  = P3V3_OCP_OV_2
  D4  OUT_D4  OUT  = P3V3_OCP_V3_2_R
  D5  IN_D5  IN  = P3V3_AUX
  D6  OUT_D6  OUT  = P3V3_OCP_V3_2_R
  D7  PG  OUT  = P3V3_OCP_PWRGD_2

PU201  MAX15090BEWIT  MAX15090BEWI+T IC  pkg BGA28_0-5_3-525X2-065  page 140
  A1  ISENSE  OUT  = P12V_OCP_SENSE_2
  A2  VCC  POWER  = P12V_OCP_VCC_2
  A3  IN_A3  IN  = P12V_AUX
  A4  OUT_A4  OUT  = P12V_OCP_V3_2
  A5  IN_A5  IN  = P12V_AUX
  A6  GATE  BI  = P12V_OCP_GATE_2
  A7  CDLY  IN  = GND
  B1  CB  BI  = P12V_OCP_CB_2
  B2  GND_B2  POWER  = GND
  B3  IN_B3  IN  = P12V_AUX
  B4  OUT_B4  OUT  = P12V_OCP_V3_2
  B5  IN_B5  IN  = P12V_AUX
  B6  OUT_B6  OUT  = P12V_OCP_V3_2
  B7  \en#\  IN  = GND
  C1  GND_C1  POWER  = GND
  C2  GND_C2  POWER  = GND
  C3  IN_C3  IN  = P12V_AUX
  C4  OUT_C4  OUT  = P12V_OCP_V3_2
  C5  IN_C5  IN  = P12V_AUX
  C6  OUT_C6  OUT  = P12V_OCP_V3_2
  C7  \fault#\  OUT  = P12V_OCP_FAULT_2
  D1  REG  OUT  = P12V_OCP_REG_2
  D2  UV  IN  = P12V_OCP_UV_2
  D3  OV  IN  = P12V_OCP_OV_2
  D4  OUT_D4  OUT  = P12V_OCP_V3_2
  D5  IN_D5  IN  = P12V_AUX
  D6  OUT_D6  OUT  = P12V_OCP_V3_2
  D7  PG  OUT  = P12V_OCP_PWRGD_2

PU202  MAX15090BEWIT  MAX15090BEWI+T IC  pkg BGA28_0-5_3-525X2-065  page 134
  A1  ISENSE  OUT  = P3V3_OCP_SENSE_1
  A2  VCC  POWER  = P3V3_OCP_VCC_1
  A3  IN_A3  IN  = P3V3_AUX
  A4  OUT_A4  OUT  = P3V3_OCP_SFF_R
  A5  IN_A5  IN  = P3V3_AUX
  A6  GATE  BI  = P3V3_OCP_GATE_PU202_1
  A7  CDLY  IN  = GND
  B1  CB  BI  = P3V3_OCP_CB_1
  B2  GND_B2  POWER  = GND
  B3  IN_B3  IN  = P3V3_AUX
  B4  OUT_B4  OUT  = P3V3_OCP_SFF_R
  B5  IN_B5  IN  = P3V3_AUX
  B6  OUT_B6  OUT  = P3V3_OCP_SFF_R
  B7  \en#\  IN  = GND
  C1  GND_C1  POWER  = GND
  C2  GND_C2  POWER  = GND
  C3  IN_C3  IN  = P3V3_AUX
  C4  OUT_C4  OUT  = P3V3_OCP_SFF_R
  C5  IN_C5  IN  = P3V3_AUX
  C6  OUT_C6  OUT  = P3V3_OCP_SFF_R
  C7  \fault#\  OUT  = P3V3_OCP_FAULT_1
  D1  REG  OUT  = P3V3_OCP_REG_1
  D2  UV  IN  = P3V3_OCP_UV_1
  D3  OV  IN  = P3V3_OCP_OV_1
  D4  OUT_D4  OUT  = P3V3_OCP_SFF_R
  D5  IN_D5  IN  = P3V3_AUX
  D6  OUT_D6  OUT  = P3V3_OCP_SFF_R
  D7  PG  OUT  = P3V3_OCP_PWRGD_1

PU203  MAX15090BEWIT  MAX15090BEWI+T IC  pkg BGA28_0-5_3-525X2-065  page 134
  A1  ISENSE  OUT  = P12V_OCP_SENSE_1
  A2  VCC  POWER  = P12V_OCP_VCC_1
  A3  IN_A3  IN  = P12V_AUX
  A4  OUT_A4  OUT  = P12V_OCP_SFF
  A5  IN_A5  IN  = P12V_AUX
  A6  GATE  BI  = P12V_OCP_GATE_1
  A7  CDLY  IN  = GND
  B1  CB  BI  = P12V_OCP_CB_1
  B2  GND_B2  POWER  = GND
  B3  IN_B3  IN  = P12V_AUX
  B4  OUT_B4  OUT  = P12V_OCP_SFF
  B5  IN_B5  IN  = P12V_AUX
  B6  OUT_B6  OUT  = P12V_OCP_SFF
  B7  \en#\  IN  = GND
  C1  GND_C1  POWER  = GND
  C2  GND_C2  POWER  = GND
  C3  IN_C3  IN  = P12V_AUX
  C4  OUT_C4  OUT  = P12V_OCP_SFF
  C5  IN_C5  IN  = P12V_AUX
  C6  OUT_C6  OUT  = P12V_OCP_SFF
  C7  \fault#\  OUT  = P12V_OCP_FAULT_1
  D1  REG  OUT  = P12V_OCP_REG_1
  D2  UV  IN  = P12V_OCP_UV_1
  D3  OV  IN  = P12V_OCP_OV_1
  D4  OUT_D4  OUT  = P12V_OCP_SFF
  D5  IN_D5  IN  = P12V_AUX
  D6  OUT_D6  OUT  = P12V_OCP_SFF
  D7  PG  OUT  = P12V_OCP_PWRGD_1

PU204  RS31312R  IC  pkg QFN22_TH_3X5  page 135
  1  EN  IN  = P12V_OCP_EN_1_R2
  2  LOADEN  IN  = GND
  3  ENTM  IN  = GND
  4  TIMER  IN  = P12V_OCP_TIMER_1
  5  ISET  IN  = P12V_OCP_ISET_1
  6  SS  IN  = P12V_OCP_SS_1
  7  GND  POWER  = GND
  8  IMON  OUT  = P12V_OCP_IMON_1
  9  FLTB  OUT  = P12V_OCP_FLTB_1
  10  PG  OUT  = HP_LVC3_OCP_V3_1_P12V_PWRGD
  11  OV  IN  = P12V_OCP_OV_FB_1
  12  AVIN  IN  = P12V_OCP_AVIN_PD_1
  13  VOUT_13  OUT  = P12V_OCP_SFF
  14  VOUT_14  OUT  = P12V_OCP_SFF
  15  VOUT_15  OUT  = P12V_OCP_SFF
  16  VOUT_16  OUT  = P12V_OCP_SFF
  17  VOUT_17  OUT  = P12V_OCP_SFF
  18  VOUT_18  OUT  = P12V_OCP_SFF
  19  VOUT_19  OUT  = P12V_OCP_SFF
  20  VOUT_20  OUT  = P12V_OCP_SFF
  21_22  VIN_21_22  IN  = P12V_AUX
  23  VIN_23  IN  = P12V_AUX
  24  VIN_24  IN  = P12V_AUX
  25  VIN_25  IN  = P12V_AUX
  26  VIN_26  IN  = P12V_AUX

PU205  MP5016GQHLZ  MP5016GQH-L-Z IC  pkg QFN8_2X1-5  page 135
  1_2  VCC  POWER  = P3V3_AUX
  3  GND  POWER  = GND
  4  ILIMIT  OUT  = P3V3_OCP_ILIMIT_1
  5  MODE  IN  = P3V3_OCP_MODE_1
  6_7  SOURCE  OUT  = P3V3_OCP_SFF_R
  8  GATE  OUT  = P3V3_OCP_GATE_1
  9  EN  IN  = P3V3_OCP_EN_1_R2
  10  DV_DT  OUT  = P3V3_OCP_DVDT_1

PU206  RS31312R  IC  pkg QFN22_TH_3X5  page 141
  1  EN  IN  = P12V_OCP_V3_2_EN_2_R3
  2  LOADEN  IN  = GND
  3  ENTM  IN  = GND
  4  TIMER  IN  = P12V_OCP_TIMER_2
  5  ISET  IN  = P12V_OCP_ISET_2
  6  SS  IN  = P12V_OCP_SS_2
  7  GND  POWER  = GND
  8  IMON  OUT  = P12V_OCP_IMON_2
  9  FLTB  OUT  = P12V_OCP_FLTB_2
  10  PG  OUT  = HP_LVC3_OCP_V3_2_P12V_PWRGD
  11  OV  IN  = P12V_OCP_OV_FB_2
  12  AVIN  IN  = P12V_OCP_AVIN_PD_2
  13  VOUT_13  OUT  = P12V_OCP_V3_2
  14  VOUT_14  OUT  = P12V_OCP_V3_2
  15  VOUT_15  OUT  = P12V_OCP_V3_2
  16  VOUT_16  OUT  = P12V_OCP_V3_2
  17  VOUT_17  OUT  = P12V_OCP_V3_2
  18  VOUT_18  OUT  = P12V_OCP_V3_2
  19  VOUT_19  OUT  = P12V_OCP_V3_2
  20  VOUT_20  OUT  = P12V_OCP_V3_2
  21_22  VIN_21_22  IN  = P12V_AUX
  23  VIN_23  IN  = P12V_AUX
  24  VIN_24  IN  = P12V_AUX
  25  VIN_25  IN  = P12V_AUX
  26  VIN_26  IN  = P12V_AUX

PU207  MP5016GQHLZ  MP5016GQH-L-Z IC  pkg QFN8_2X1-5  page 141
  1_2  VCC  POWER  = P3V3_AUX
  3  GND  POWER  = GND
  4  ILIMIT  OUT  = P3V3_OCP_ILIMIT_2
  5  MODE  IN  = P3V3_OCP_MODE_2
  6_7  SOURCE  OUT  = P3V3_OCP_V3_2_R
  8  GATE  OUT  = P3V3_OCP_GATE_PU207_2
  9  EN  IN  = P3V3_OCP_EN_2
  10  DV_DT  OUT  = P3V3_OCP_DVDT_2

PU287  MP5991GLUZ  MP5991GLU-Z IC  pkg LGA32_TH_0-5_5X5  page 263
  1  VOUT1  OUT  = P12V_AUX
  2  VOUT2  OUT  = P12V_AUX
  3  D_OC  OUT  = HSC_D_OC_1
  4  \on\  IN  = HSC_ON
  5  GOK  OUT  = HSC_FAULT
  6  FLT_TYPE  IN  = HSC_FLT_TYPE_1
  7  NC1  TRI  = HSC_NC1_1
  8  MODE  IN  = HSC_MODE_1
  9  VIN1  IN  = P12V_PSU
  10  VIN2  IN  = P12V_PSU
  11  VIN3  IN  = P12V_PSU
  12  VIN4  IN  = P12V_PSU
  13  VIN5  IN  = P12V_PSU
  14  VIN6  IN  = P12V_PSU
  15  VIN7  IN  = P12V_PSU
  16  VIN8  IN  = P12V_PSU
  17  SCREF_OCWREF  IN  = HSC_SCREF_1
  18  VTEMP  OUT  = HSC_VTEMP
  19  SS  IN  = HSC_SS
  20  GND  POWER  = AGND_HSC
  21  VDD33  POWER  = HSC_VDD_R_1
  22  IMON  OUT  = HSC_IMON
  23  CS  OUT  = HSC_CS_1
  24  OCREF  OUT  = HSC_OCREF
  25  VOUT3  OUT  = P12V_AUX
  26  VOUT4  OUT  = P12V_AUX
  27  VOUT5  OUT  = P12V_AUX
  28  VOUT6  OUT  = P12V_AUX
  29  VOUT7  OUT  = P12V_AUX
  30  VOUT8  OUT  = P12V_AUX
  31  VOUT9  OUT  = P12V_AUX
  32  VOUT10  OUT  = P12V_AUX
  33  VIN9  IN  = P12V_PSU

PU288  MP5991GLUZ  MP5991GLU-Z IC  pkg LGA32_TH_0-5_5X5  page 263
  1  VOUT1  OUT  = P12V_AUX
  2  VOUT2  OUT  = P12V_AUX
  3  D_OC  OUT  = HSC_D_OC_2
  4  \on\  IN  = HSC_ON
  5  GOK  OUT  = HSC_FAULT
  6  FLT_TYPE  IN  = HSC_FLT_TYPE_2
  7  NC1  TRI  = HSC_NC1_2
  8  MODE  IN  = HSC_MODE_2
  9  VIN1  IN  = P12V_PSU
  10  VIN2  IN  = P12V_PSU
  11  VIN3  IN  = P12V_PSU
  12  VIN4  IN  = P12V_PSU
  13  VIN5  IN  = P12V_PSU
  14  VIN6  IN  = P12V_PSU
  15  VIN7  IN  = P12V_PSU
  16  VIN8  IN  = P12V_PSU
  17  SCREF_OCWREF  IN  = HSC_SCREF_2
  18  VTEMP  OUT  = HSC_VTEMP
  19  SS  IN  = HSC_SS
  20  GND  POWER  = AGND_HSC
  21  VDD33  POWER  = HSC_VDD_R_2
  22  IMON  OUT  = HSC_IMON
  23  CS  OUT  = HSC_CS_2
  24  OCREF  OUT  = HSC_OCREF
  25  VOUT3  OUT  = P12V_AUX
  26  VOUT4  OUT  = P12V_AUX
  27  VOUT5  OUT  = P12V_AUX
  28  VOUT6  OUT  = P12V_AUX
  29  VOUT7  OUT  = P12V_AUX
  30  VOUT8  OUT  = P12V_AUX
  31  VOUT9  OUT  = P12V_AUX
  32  VOUT10  OUT  = P12V_AUX
  33  VIN9  IN  = P12V_PSU

PU289  MP5990GMA1111Z  MP5990GMA-1111-Z IC  pkg LGA45_TH_0-45_7X5  page 262
  1  VIN1  IN  = P12V_PSU
  2  VIN2  IN  = P12V_PSU
  3  VIN3  IN  = P12V_PSU
  4  VIN4  IN  = P12V_PSU
  5  VIN5  IN  = P12V_PSU
  6  VIN6  IN  = P12V_PSU
  7  VIN7  IN  = P12V_PSU
  8  VIN8  IN  = P12V_PSU
  9  VINSEN  IN  = HSC_VSENSE
  10  \alt#\  OUT  = IRQ_SML1_PMBUS_ALERT
  11  SCL  IN  = SMB_SML1_PMBUS_HSC_L_SCL
  12  SDA  BI  = SMB_SML1_PMBUS_HSC_R_SDA
  13  \pg||ocw#\  OUT  = MB0_P12V_STBY_PWRGD
  14  \vin_uvw#\  OUT  = HSC_VIN_UVW_N
  15  VTEMP  IN  = HSC_VTEMP
  16  SS  OUT  = HSC_SS
  17  VDD33_1  POWER  = HSC_VDD_R
  18  GND1  POWER  = AGND_HSC
  19  VDD18  POWER  = HSC_VDD18
  20  CS  OUT  = HSC_CS
  21  IMON  BI  = HSC_IMON
  22  OCREF  OUT  = HSC_OCREF
  23  ADDR  IN  = HSC_ADDR
  24  VOSEN  IN  = HSC_VOSEN
  25  SCREF_OCWREF  OUT  = HSC_SCREF
  26  EN  IN  = HSC_EN_R
  27  VOUT1  OUT  = P12V_AUX
  28  VOUT2  OUT  = P12V_AUX
  29  VOUT3  OUT  = P12V_AUX
  30  VOUT4  OUT  = P12V_AUX
  31  VOUT5  OUT  = P12V_AUX
  32  VOUT6  OUT  = P12V_AUX
  33  VOUT7  OUT  = P12V_AUX
  34  VOUT8  OUT  = P12V_AUX
  35  VOUT9  OUT  = P12V_AUX
  36  VOUT10  OUT  = P12V_AUX
  37  D_OC  OUT  = HSC_D_OC_R
  38  \on\  OUT  = HSC_ON_R
  39  GOK  BI  = HSC_FAULT
  40  FLT_TYPE  IN  = HSC_FLT_TYPE
  41  MODE  IN  = HSC_MODE
  42  VIN9  IN  = P12V_PSU
  43  VIN10  IN  = P12V_PSU
  44  GND2  POWER  = AGND_HSC
  45  VDD33_2  POWER  = HSC_VDD_R

PU292  RS31312R  IC  pkg QFN22_TH_3X5  page 147
  1  EN  IN  = P12V_E1S_EN_0_R2
  2  LOADEN  IN  = GND
  3  ENTM  IN  = GND
  4  TIMER  IN  = P12V_E1S_TIMER_0
  5  ISET  IN  = P12V_E1S_ISET_0
  6  SS  IN  = P12V_E1S_SS_0
  7  GND  POWER  = GND
  8  IMON  OUT  = P12V_E1S_IMON_0
  9  FLTB  OUT  = P12V_E1S_FLTB_0
  10  PG  OUT  = HP_LVC3_E1S_0_HSC_PWRGD
  11  OV  IN  = P12V_E1S_OV_FB_0
  12  AVIN  IN  = P12V_E1S_AVIN_PD_0
  13  VOUT_13  OUT  = P12V_E1S_0
  14  VOUT_14  OUT  = P12V_E1S_0
  15  VOUT_15  OUT  = P12V_E1S_0
  16  VOUT_16  OUT  = P12V_E1S_0
  17  VOUT_17  OUT  = P12V_E1S_0
  18  VOUT_18  OUT  = P12V_E1S_0
  19  VOUT_19  OUT  = P12V_E1S_0
  20  VOUT_20  OUT  = P12V_E1S_0
  21_22  VIN_21_22  IN  = P12V_AUX
  23  VIN_23  IN  = P12V_AUX
  24  VIN_24  IN  = P12V_AUX
  25  VIN_25  IN  = P12V_AUX
  26  VIN_26  IN  = P12V_AUX

PU293  MP5016GQHLZ  MP5016GQH-L-Z IC  pkg QFN8_2X1-5  page 147
  1_2  VCC  POWER  = P3V3_AUX
  3  GND  POWER  = GND
  4  ILIMIT  OUT  = P3V3_E1S_ILIMIT_0
  5  MODE  IN  = P3V3_E1S_MODE_0
  6_7  SOURCE  OUT  = P3V3_E1S_0_R
  8  GATE  OUT  = P3V3_E1S_GATE_0_PU293
  9  EN  IN  = P3V3_E1S_EN_0_R2
  10  DV_DT  OUT  = P3V3_E1S_DVDT_0

PU294  MAX15090BEWIT  MAX15090BEWI+T IC  pkg BGA28_0-5_3-525X2-065  page 146
  A1  ISENSE  OUT  = P12V_E1S_SENSE_0
  A2  VCC  POWER  = P12V_E1S_VCC_0
  A3  IN_A3  IN  = P12V_AUX
  A4  OUT_A4  OUT  = P12V_E1S_0
  A5  IN_A5  IN  = P12V_AUX
  A6  GATE  BI  = P12V_E1S_GATE_0
  A7  CDLY  IN  = GND
  B1  CB  BI  = P12V_E1S_CB_0
  B2  GND_B2  POWER  = GND
  B3  IN_B3  IN  = P12V_AUX
  B4  OUT_B4  OUT  = P12V_E1S_0
  B5  IN_B5  IN  = P12V_AUX
  B6  OUT_B6  OUT  = P12V_E1S_0
  B7  \en#\  IN  = GND
  C1  GND_C1  POWER  = GND
  C2  GND_C2  POWER  = GND
  C3  IN_C3  IN  = P12V_AUX
  C4  OUT_C4  OUT  = P12V_E1S_0
  C5  IN_C5  IN  = P12V_AUX
  C6  OUT_C6  OUT  = P12V_E1S_0
  C7  \fault#\  OUT  = P12V_E1S_FAULT_0
  D1  REG  OUT  = P12V_E1S_REG_0
  D2  UV  IN  = P12V_E1S_UV_0
  D3  OV  IN  = P12V_E1S_OV_0
  D4  OUT_D4  OUT  = P12V_E1S_0
  D5  IN_D5  IN  = P12V_AUX
  D6  OUT_D6  OUT  = P12V_E1S_0
  D7  PG  OUT  = P12V_E1S_PWRGD_0

PU295  MAX15090BEWIT  MAX15090BEWI+T IC  pkg BGA28_0-5_3-525X2-065  page 146
  A1  ISENSE  OUT  = P3V3_E1S_SENSE_0
  A2  VCC  POWER  = P3V3_E1S_VCC_0
  A3  IN_A3  IN  = P3V3_AUX
  A4  OUT_A4  OUT  = P3V3_E1S_0_R
  A5  IN_A5  IN  = P3V3_AUX
  A6  GATE  BI  = P3V3_E1S_GATE_0
  A7  CDLY  IN  = GND
  B1  CB  BI  = P3V3_E1S_CB_0
  B2  GND_B2  POWER  = GND
  B3  IN_B3  IN  = P3V3_AUX
  B4  OUT_B4  OUT  = P3V3_E1S_0_R
  B5  IN_B5  IN  = P3V3_AUX
  B6  OUT_B6  OUT  = P3V3_E1S_0_R
  B7  \en#\  IN  = GND
  C1  GND_C1  POWER  = GND
  C2  GND_C2  POWER  = GND
  C3  IN_C3  IN  = P3V3_AUX
  C4  OUT_C4  OUT  = P3V3_E1S_0_R
  C5  IN_C5  IN  = P3V3_AUX
  C6  OUT_C6  OUT  = P3V3_E1S_0_R
  C7  \fault#\  OUT  = P3V3_E1S_FAULT_0
  D1  REG  OUT  = P3V3_E1S_REG_0
  D2  UV  IN  = P3V3_E1S_UV_0
  D3  OV  IN  = P3V3_E1S_OV_0
  D4  OUT_D4  OUT  = P3V3_E1S_0_R
  D5  IN_D5  IN  = P3V3_AUX
  D6  OUT_D6  OUT  = P3V3_E1S_0_R
  D7  PG  OUT  = P3V3_E1S_PWRGD_0

PU296  MP5991GLUZ  MP5991GLU-Z IC  pkg LGA32_TH_0-5_5X5  page 264
  1  VOUT1  OUT  = P12V_AUX
  2  VOUT2  OUT  = P12V_AUX
  3  D_OC  OUT  = HSC_D_OC_3
  4  \on\  IN  = HSC_ON
  5  GOK  OUT  = HSC_FAULT
  6  FLT_TYPE  IN  = HSC_FLT_TYPE_3
  7  NC1  TRI  = HSC_NC1_3
  8  MODE  IN  = HSC_MODE_3
  9  VIN1  IN  = P12V_PSU
  10  VIN2  IN  = P12V_PSU
  11  VIN3  IN  = P12V_PSU
  12  VIN4  IN  = P12V_PSU
  13  VIN5  IN  = P12V_PSU
  14  VIN6  IN  = P12V_PSU
  15  VIN7  IN  = P12V_PSU
  16  VIN8  IN  = P12V_PSU
  17  SCREF_OCWREF  IN  = HSC_SCREF_3
  18  VTEMP  OUT  = HSC_VTEMP
  19  SS  IN  = HSC_SS
  20  GND  POWER  = AGND_HSC
  21  VDD33  POWER  = HSC_VDD_R_3
  22  IMON  OUT  = HSC_IMON
  23  CS  OUT  = HSC_CS_3
  24  OCREF  OUT  = HSC_OCREF
  25  VOUT3  OUT  = P12V_AUX
  26  VOUT4  OUT  = P12V_AUX
  27  VOUT5  OUT  = P12V_AUX
  28  VOUT6  OUT  = P12V_AUX
  29  VOUT7  OUT  = P12V_AUX
  30  VOUT8  OUT  = P12V_AUX
  31  VOUT9  OUT  = P12V_AUX
  32  VOUT10  OUT  = P12V_AUX
  33  VIN9  IN  = P12V_PSU

PU297  MP5991GLUZ  MP5991GLU-Z IC  pkg LGA32_TH_0-5_5X5  page 264
  1  VOUT1  OUT  = P12V_AUX
  2  VOUT2  OUT  = P12V_AUX
  3  D_OC  OUT  = HSC_D_OC_4
  4  \on\  IN  = HSC_ON
  5  GOK  OUT  = HSC_FAULT
  6  FLT_TYPE  IN  = HSC_FLT_TYPE_4
  7  NC1  TRI  = HSC_NC1_4
  8  MODE  IN  = HSC_MODE_4
  9  VIN1  IN  = P12V_PSU
  10  VIN2  IN  = P12V_PSU
  11  VIN3  IN  = P12V_PSU
  12  VIN4  IN  = P12V_PSU
  13  VIN5  IN  = P12V_PSU
  14  VIN6  IN  = P12V_PSU
  15  VIN7  IN  = P12V_PSU
  16  VIN8  IN  = P12V_PSU
  17  SCREF_OCWREF  IN  = HSC_SCREF_4
  18  VTEMP  OUT  = HSC_VTEMP
  19  SS  IN  = HSC_SS
  20  GND  POWER  = AGND_HSC
  21  VDD33  POWER  = HSC_VDD_R_4
  22  IMON  OUT  = HSC_IMON
  23  CS  OUT  = HSC_CS_4
  24  OCREF  OUT  = HSC_OCREF
  25  VOUT3  OUT  = P12V_AUX
  26  VOUT4  OUT  = P12V_AUX
  27  VOUT5  OUT  = P12V_AUX
  28  VOUT6  OUT  = P12V_AUX
  29  VOUT7  OUT  = P12V_AUX
  30  VOUT8  OUT  = P12V_AUX
  31  VOUT9  OUT  = P12V_AUX
  32  VOUT10  OUT  = P12V_AUX
  33  VIN9  IN  = P12V_PSU
